# T6G (Grand Teton) — schematic netlist excerpt (pin names and nets, part order shuffled) for the footprints in the layout excerpt that follows; sources: Cadence DE-HDL packaged netlist, KiCad conversion of 04192023_DAF0TMB3IC0_F0TG_MB_C_brd_V02_OCP.brd

R4193  Q_RES  1K 1% CHIP  pkg 0402LF  page 235 : A = U273_3_ADD1 ; B = GND
R6787  Q_RES  1K 1% CHIP  pkg 0402LF  page 364 : A = P0V9_RETIMER_CPU1_EN0_R ; B = GND

(kicad_pcb
	(version 20260206)
	(generator "pcbnew")
	(generator_version "10.0")
	(general
		(thickness 1.6)
		(legacy_teardrops no)
	)
	(paper "A4")
	(title_block
		(title "04192023_DAF0TMB3IC0_F0TG_MB_C_brd_V02_OCP.brd")
		(comment 1 "Grand Teton / footprints 1965-1966 of 8354")
	)
	(layers
		(0 "F.Cu" signal "TOP")
		(4 "In1.Cu" signal "GND")
		(6 "In2.Cu" signal "IN1")
		(8 "In3.Cu" signal "GND1")
		(10 "In4.Cu" signal "IN2")
		(12 "In5.Cu" signal "GND2")
		(14 "In6.Cu" signal "IN3")
		(16 "In7.Cu" signal "GND3")
		(18 "In8.Cu" signal "VCC")
		(20 "In9.Cu" signal "VCC1")
		(22 "In10.Cu" signal "GND4")
		(24 "In11.Cu" signal "IN4")
		(26 "In12.Cu" signal "GND5")
		(28 "In13.Cu" signal "IN5")
		(30 "In14.Cu" signal "GND6")
		(32 "In15.Cu" signal "IN6")
		(34 "In16.Cu" signal "GND7")
		(2 "B.Cu" signal "BOTTOM")
		(9 "F.Adhes" user "F.Adhesive")
		(11 "B.Adhes" user "B.Adhesive")
		(13 "F.Paste" user "Package Geometry/Pastemask Top")
		(15 "B.Paste" user "Package Geometry/Pastemask Bottom")
		(5 "F.SilkS" user "Ref Des/Silkscreen Top")
		(7 "B.SilkS" user "Ref Des/Silkscreen Bottom")
		(1 "F.Mask" user "Board Geometry/Soldermask Top")
		(3 "B.Mask" user "Board Geometry/Soldermask Bottom")
		(17 "Dwgs.User" user "User.Drawings")
		(19 "Cmts.User" user "User.Comments")
		(21 "Eco1.User" user "User.Eco1")
		(23 "Eco2.User" user "User.Eco2")
		(25 "Edge.Cuts" user "Board Geometry/Outline")
		(27 "Margin" user)
		(31 "F.CrtYd" user "Package Geometry/Place Bound Top")
		(29 "B.CrtYd" user "Package Geometry/Place Bound Bottom")
		(35 "F.Fab" user "Ref Des/Assembly Top")
		(33 "B.Fab" user "Ref Des/Assembly Bottom")
	)
	(footprint ""
		(layer "F.Cu")
		(at 120.358662 -15.247366)
		(property "Reference" "R4193"
			(at 0 0 0)
			(layer "F.SilkS")
			(hide yes)
			(effects
				(font
					(size 1.27 1.27)
				)
			)
		)
		(property "Value" ""
			(at 0 0 0)
			(layer "F.Fab")
			(effects
				(font
					(size 1.27 1.27)
				)
			)
		)
		(duplicate_pad_numbers_are_jumpers no)
		(fp_line
			(start -0.7874 -0.4064)
			(end 0.7874 -0.4064)
			(stroke
				(width 0.1524)
				(type default)
			)
			(layer "F.SilkS")
		)
		(fp_line
			(start -0.7874 0.4064)
			(end -0.7874 -0.4064)
			(stroke
				(width 0.1524)
				(type default)
			)
			(layer "F.SilkS")
		)
		(fp_line
			(start 0.7874 -0.4064)
			(end 0.7874 0.4064)
			(stroke
				(width 0.1524)
				(type default)
			)
			(layer "F.SilkS")
		)
		(fp_line
			(start 0.7874 0.4064)
			(end -0.7874 0.4064)
			(stroke
				(width 0.1524)
				(type default)
			)
			(layer "F.SilkS")
		)
		(fp_line
			(start -0.67945 -0.305054)
			(end -0.12065 -0.305054)
			(stroke
				(width 0.1)
				(type default)
			)
			(layer "F.Fab")
		)
		(fp_line
			(start -0.67945 0.3048)
			(end -0.67945 -0.305054)
			(stroke
				(width 0.1)
				(type default)
			)
			(layer "F.Fab")
		)
		(fp_line
			(start -0.12065 -0.305054)
			(end -0.12065 -0.2794)
			(stroke
				(width 0.1)
				(type default)
			)
			(layer "F.Fab")
		)
		(fp_line
			(start -0.12065 -0.2794)
			(end 0.12065 -0.2794)
			(stroke
				(width 0.1)
				(type default)
			)
			(layer "F.Fab")
		)
		(fp_line
			(start -0.12065 0.2794)
			(end -0.12065 0.3048)
			(stroke
				(width 0.1)
				(type default)
			)
			(layer "F.Fab")
		)
		(fp_line
			(start -0.12065 0.3048)
			(end -0.67945 0.3048)
			(stroke
				(width 0.1)
				(type default)
			)
			(layer "F.Fab")
		)
		(fp_line
			(start 0.120396 0.2794)
			(end -0.12065 0.2794)
			(stroke
				(width 0.1)
				(type default)
			)
			(layer "F.Fab")
		)
		(fp_line
			(start 0.120396 0.3048)
			(end 0.120396 0.2794)
			(stroke
				(width 0.1)
				(type default)
			)
			(layer "F.Fab")
		)
		(fp_line
			(start 0.12065 -0.3048)
			(end 0.67945 -0.3048)
			(stroke
				(width 0.1)
				(type default)
			)
			(layer "F.Fab")
		)
		(fp_line
			(start 0.12065 -0.2794)
			(end 0.12065 -0.3048)
			(stroke
				(width 0.1)
				(type default)
			)
			(layer "F.Fab")
		)
		(fp_line
			(start 0.67945 -0.3048)
			(end 0.67945 0.3048)
			(stroke
				(width 0.1)
				(type default)
			)
			(layer "F.Fab")
		)
		(fp_line
			(start 0.67945 0.3048)
			(end 0.120396 0.3048)
			(stroke
				(width 0.1)
				(type default)
			)
			(layer "F.Fab")
		)
		(pad "1" smd circle
			(at -0.40005 0)
			(size 0 0)
			(layers "F.Cu" "F.Mask" "F.Paste")
			(net "U273_3_ADD1")
		)
		(pad "2" smd circle
			(at 0.40005 0)
			(size 0 0)
			(layers "F.Cu" "F.Mask" "F.Paste")
			(net "GND")
		)
	)
	(footprint ""
		(layer "F.Cu")
		(at 19.915124 -407.976578 -90)
		(property "Reference" "R6787"
			(at 0 0 270)
			(layer "F.SilkS")
			(hide yes)
			(effects
				(font
					(size 1.27 1.27)
				)
			)
		)
		(property "Value" ""
			(at 0 0 270)
			(layer "F.Fab")
			(effects
				(font
					(size 1.27 1.27)
				)
			)
		)
		(duplicate_pad_numbers_are_jumpers no)
		(fp_line
			(start -0.7874 0.4064)
			(end -0.7874 -0.4064)
			(stroke
				(width 0.1524)
				(type default)
			)
			(layer "F.SilkS")
		)
		(fp_line
			(start 0.7874 0.4064)
			(end -0.7874 0.4064)
			(stroke
				(width 0.1524)
				(type default)
			)
			(layer "F.SilkS")
		)
		(fp_line
			(start -0.7874 -0.4064)
			(end 0.7874 -0.4064)
			(stroke
				(width 0.1524)
				(type default)
			)
			(layer "F.SilkS")
		)
		(fp_line
			(start 0.7874 -0.4064)
			(end 0.7874 0.4064)
			(stroke
				(width 0.1524)
				(type default)
			)
			(layer "F.SilkS")
		)
		(fp_line
			(start -0.67945 0.3048)
			(end -0.67945 -0.305054)
			(stroke
				(width 0.1)
				(type default)
			)
			(layer "F.Fab")
		)
		(fp_line
			(start -0.12065 0.3048)
			(end -0.67945 0.3048)
			(stroke
				(width 0.1)
				(type default)
			)
			(layer "F.Fab")
		)
		(fp_line
			(start 0.120396 0.3048)
			(end 0.120396 0.2794)
			(stroke
				(width 0.1)
				(type default)
			)
			(layer "F.Fab")
		)
		(fp_line
			(start 0.67945 0.3048)
			(end 0.120396 0.3048)
			(stroke
				(width 0.1)
				(type default)
			)
			(layer "F.Fab")
		)
		(fp_line
			(start -0.12065 0.2794)
			(end -0.12065 0.3048)
			(stroke
				(width 0.1)
				(type default)
			)
			(layer "F.Fab")
		)
		(fp_line
			(start 0.120396 0.2794)
			(end -0.12065 0.2794)
			(stroke
				(width 0.1)
				(type default)
			)
			(layer "F.Fab")
		)
		(fp_line
			(start -0.12065 -0.2794)
			(end 0.12065 -0.2794)
			(stroke
				(width 0.1)
				(type default)
			)
			(layer "F.Fab")
		)
		(fp_line
			(start 0.12065 -0.2794)
			(end 0.12065 -0.3048)
			(stroke
				(width 0.1)
				(type default)
			)
			(layer "F.Fab")
		)
		(fp_line
			(start 0.12065 -0.3048)
			(end 0.67945 -0.3048)
			(stroke
				(width 0.1)
				(type default)
			)
			(layer "F.Fab")
		)
		(fp_line
			(start 0.67945 -0.3048)
			(end 0.67945 0.3048)
			(stroke
				(width 0.1)
				(type default)
			)
			(layer "F.Fab")
		)
		(fp_line
			(start -0.67945 -0.305054)
			(end -0.12065 -0.305054)
			(stroke
				(width 0.1)
				(type default)
			)
			(layer "F.Fab")
		)
		(fp_line
			(start -0.12065 -0.305054)
			(end -0.12065 -0.2794)
			(stroke
				(width 0.1)
				(type default)
			)
			(layer "F.Fab")
		)
		(pad "1" smd circle
			(at -0.40005 0 270)
			(size 0 0)
			(layers "F.Cu" "F.Mask" "F.Paste")
			(net "P0V9_RETIMER_CPU1_EN0_R")
		)
		(pad "2" smd circle
			(at 0.40005 0 270)
			(size 0 0)
			(layers "F.Cu" "F.Mask" "F.Paste")
			(net "GND")
		)
	)
)
